FILE_TYPE = CONNECTIVITY;
{Allegro Design Entry HDL 17.2-2016 S081 (4005846) 1/11/2022}
"PAGE_NUMBER" = 168;
0"NC";
1"P5E_CPU1_PE4_TX_DN<15:8>";
2"P5E_CPU1_PE4_TX_C_DN<15:8>";
3"P5E_CPU1_PE4_TX_DP<15:8>";
4"P5E_CPU1_PE4_TX_C_DP<15:8>";
5"P5E_CPU1_PE4_TX_DP<7:0>";
6"P5E_CPU1_PE4_TX_DN<7:0>";
7"P5E_CPU1_PE4_TX_C_DP<7:0>";
8"P5E_CPU1_PE4_TX_C_DN<7:0>";
9"P5E_CPU1_PE3_TX_DP<7:0>";
10"P5E_CPU1_PE3_TX_DN<7:0>";
11"P5E_CPU1_PE3_TX_C_DN<7:0>";
12"P5E_CPU1_PE3_TX_DP<15:8>";
13"P5E_CPU1_PE3_TX_DN<15:8>";
14"P5E_CPU1_PE3_TX_C_DP<7:0>";
15"P5E_CPU1_PE3_TX_C_DN<15:8>";
16"P5E_CPU1_PE3_TX_C_DP<15:8>";
17"P5E_CPU1_PE3_TX_C_DN<4>";
18"P5E_CPU1_PE4_TX_DP<2>";
19"P5E_CPU1_PE4_TX_DN<2>";
20"P5E_CPU1_PE3_TX_C_DP<6>";
21"P5E_CPU1_PE3_TX_DN<12>";
22"P5E_CPU1_PE3_TX_C_DP<14>";
23"P5E_CPU1_PE3_TX_C_DN<14>";
24"P5E_CPU1_PE3_TX_C_DP<15>";
25"P5E_CPU1_PE3_TX_C_DN<15>";
26"P5E_CPU1_PE3_TX_C_DP<0>";
27"P5E_CPU1_PE3_TX_C_DP<1>";
28"P5E_CPU1_PE3_TX_C_DN<1>";
29"P5E_CPU1_PE3_TX_C_DP<2>";
30"P5E_CPU1_PE3_TX_C_DP<3>";
31"P5E_CPU1_PE3_TX_C_DP<4>";
32"P5E_CPU1_PE3_TX_C_DP<8>";
33"P5E_CPU1_PE3_TX_DP<5>";
34"P5E_CPU1_PE3_TX_C_DN<3>";
35"P5E_CPU1_PE3_TX_C_DN<2>";
36"P5E_CPU1_PE3_TX_DP<1>";
37"P5E_CPU1_PE3_TX_C_DN<5>";
38"P5E_CPU1_PE3_TX_C_DP<5>";
39"P5E_CPU1_PE3_TX_C_DP<11>";
40"P5E_CPU1_PE3_TX_C_DP<12>";
41"P5E_CPU1_PE3_TX_C_DP<10>";
42"P5E_CPU1_PE3_TX_C_DP<9>";
43"P5E_CPU1_PE3_TX_C_DN<12>";
44"P5E_CPU1_PE3_TX_C_DN<11>";
45"P5E_CPU1_PE3_TX_C_DN<10>";
46"P5E_CPU1_PE3_TX_C_DN<8>";
47"P5E_CPU1_PE3_TX_C_DN<9>";
48"P5E_CPU1_PE3_TX_C_DP<13>";
49"P5E_CPU1_PE3_TX_C_DN<13>";
50"P5E_CPU1_PE3_TX_C_DP<7>";
51"P5E_CPU1_PE3_TX_C_DN<7>";
52"P5E_CPU1_PE3_TX_C_DN<6>";
53"P5E_CPU1_PE3_TX_DP<4>";
54"P5E_CPU1_PE3_TX_DP<7>";
55"P5E_CPU1_PE3_TX_DP<6>";
56"P5E_CPU1_PE3_TX_DP<3>";
57"P5E_CPU1_PE3_TX_DN<4>";
58"P5E_CPU1_PE3_TX_DN<3>";
59"P5E_CPU1_PE3_TX_DN<7>";
60"P5E_CPU1_PE3_TX_DN<6>";
61"P5E_CPU1_PE3_TX_DN<5>";
62"P5E_CPU1_PE3_TX_DN<11>";
63"P5E_CPU1_PE3_TX_DP<14>";
64"P5E_CPU1_PE3_TX_DP<15>";
65"P5E_CPU1_PE3_TX_DP<8>";
66"P5E_CPU1_PE3_TX_DP<11>";
67"P5E_CPU1_PE3_TX_DP<9>";
68"P5E_CPU1_PE3_TX_DP<12>";
69"P5E_CPU1_PE3_TX_DP<10>";
70"P5E_CPU1_PE3_TX_DN<8>";
71"P5E_CPU1_PE3_TX_DN<9>";
72"P5E_CPU1_PE3_TX_DN<10>";
73"P5E_CPU1_PE3_TX_DN<14>";
74"P5E_CPU1_PE3_TX_DN<13>";
75"P5E_CPU1_PE3_TX_DN<15>";
76"P5E_CPU1_PE3_TX_DP<13>";
77"P5E_CPU1_PE3_TX_C_DN<0>";
78"P5E_CPU1_PE3_TX_DP<2>";
79"P5E_CPU1_PE3_TX_DN<2>";
80"P5E_CPU1_PE3_TX_DN<1>";
81"P5E_CPU1_PE3_TX_DN<0>";
82"P5E_CPU1_PE3_TX_DP<0>";
83"P5E_CPU1_PE4_TX_C_DP<0>";
84"P5E_CPU1_PE4_TX_C_DN<0>";
85"P5E_CPU1_PE4_TX_DN<1>";
86"P5E_CPU1_PE4_TX_DP<3>";
87"P5E_CPU1_PE4_TX_DN<3>";
88"P5E_CPU1_PE4_TX_DP<4>";
89"P5E_CPU1_PE4_TX_DN<4>";
90"P5E_CPU1_PE4_TX_C_DN<14>";
91"P5E_CPU1_PE4_TX_C_DN<13>";
92"P5E_CPU1_PE4_TX_C_DN<15>";
93"P5E_CPU1_PE4_TX_C_DP<15>";
94"P5E_CPU1_PE4_TX_C_DP<14>";
95"P5E_CPU1_PE4_TX_C_DP<13>";
96"P5E_CPU1_PE4_TX_C_DN<9>";
97"P5E_CPU1_PE4_TX_C_DN<8>";
98"P5E_CPU1_PE4_TX_C_DN<10>";
99"P5E_CPU1_PE4_TX_C_DN<12>";
100"P5E_CPU1_PE4_TX_C_DP<10>";
101"P5E_CPU1_PE4_TX_C_DP<12>";
102"P5E_CPU1_PE4_TX_C_DP<8>";
103"P5E_CPU1_PE4_TX_DN<15>";
104"P5E_CPU1_PE4_TX_DN<13>";
105"P5E_CPU1_PE4_TX_DN<14>";
106"P5E_CPU1_PE4_TX_DN<9>";
107"P5E_CPU1_PE4_TX_DP<12>";
108"P5E_CPU1_PE4_TX_DP<9>";
109"P5E_CPU1_PE4_TX_DP<11>";
110"P5E_CPU1_PE4_TX_DP<13>";
111"P5E_CPU1_PE4_TX_DP<15>";
112"P5E_CPU1_PE4_TX_DP<14>";
113"P5E_CPU1_PE4_TX_C_DN<5>";
114"P5E_CPU1_PE4_TX_C_DN<6>";
115"P5E_CPU1_PE4_TX_C_DN<7>";
116"P5E_CPU1_PE4_TX_C_DP<5>";
117"P5E_CPU1_PE4_TX_C_DP<7>";
118"P5E_CPU1_PE4_TX_C_DP<6>";
119"P5E_CPU1_PE4_TX_C_DN<1>";
120"P5E_CPU1_PE4_TX_C_DN<2>";
121"P5E_CPU1_PE4_TX_C_DN<3>";
122"P5E_CPU1_PE4_TX_C_DP<4>";
123"P5E_CPU1_PE4_TX_C_DP<2>";
124"P5E_CPU1_PE4_TX_C_DP<3>";
125"P5E_CPU1_PE4_TX_C_DN<4>";
126"P5E_CPU1_PE4_TX_C_DP<1>";
127"P5E_CPU1_PE4_TX_DN<5>";
128"P5E_CPU1_PE4_TX_DN<6>";
129"P5E_CPU1_PE4_TX_DN<7>";
130"P5E_CPU1_PE4_TX_DN<0>";
131"P5E_CPU1_PE4_TX_DP<1>";
132"P5E_CPU1_PE4_TX_DP<0>";
133"P5E_CPU1_PE4_TX_DP<6>";
134"P5E_CPU1_PE4_TX_DP<5>";
135"P5E_CPU1_PE4_TX_DP<7>";
136"P5E_CPU1_PE4_TX_DP<8>";
137"P5E_CPU1_PE4_TX_DN<8>";
138"P5E_CPU1_PE4_TX_C_DP<9>";
139"P5E_CPU1_PE4_TX_C_DP<11>";
140"P5E_CPU1_PE4_TX_DN<10>";
141"P5E_CPU1_PE4_TX_DP<10>";
142"P5E_CPU1_PE4_TX_DN<12>";
143"P5E_CPU1_PE4_TX_C_DN<11>";
144"P5E_CPU1_PE4_TX_DN<11>";
%"TAP"
"1","(2175,125)","2","standard","I109";
;
CDS_LIB"standard"
BODY_TYPE"PLUMBING"
HDL_TAP"TRUE";
"B \NAC \NWC"5;
"S \NAC"
BN"0"132;
%"TAP"
"1","(2175,325)","2","standard","I110";
;
CDS_LIB"standard"
BODY_TYPE"PLUMBING"
HDL_TAP"TRUE";
"B \NAC \NWC"5;
"S \NAC"
BN"1"131;
%"TAP"
"1","(2425,175)","2","standard","I111";
;
CDS_LIB"standard"
BODY_TYPE"PLUMBING"
HDL_TAP"TRUE";
"B \NAC \NWC"6;
"S \NAC"
BN"0"130;
%"TAP"
"1","(2425,375)","2","standard","I112";
;
CDS_LIB"standard"
BODY_TYPE"PLUMBING"
HDL_TAP"TRUE";
"B \NAC \NWC"6;
"S \NAC"
BN"1"85;
%"TAP"
"1","(2175,525)","2","standard","I113";
;
CDS_LIB"standard"
BODY_TYPE"PLUMBING"
HDL_TAP"TRUE";
"B \NAC \NWC"5;
"S \NAC"
BN"2"18;
%"TAP"
"1","(2175,925)","2","standard","I114";
;
CDS_LIB"standard"
BODY_TYPE"PLUMBING"
HDL_TAP"TRUE";
"B \NAC \NWC"5;
"S \NAC"
BN"4"88;
%"TAP"
"1","(2175,725)","2","standard","I115";
;
CDS_LIB"standard"
BODY_TYPE"PLUMBING"
HDL_TAP"TRUE";
"B \NAC \NWC"5;
"S \NAC"
BN"3"86;
%"TAP"
"1","(2425,575)","2","standard","I116";
;
CDS_LIB"standard"
BODY_TYPE"PLUMBING"
HDL_TAP"TRUE";
"B \NAC \NWC"6;
"S \NAC"
BN"2"19;
%"TAP"
"1","(2425,775)","2","standard","I117";
;
CDS_LIB"standard"
BODY_TYPE"PLUMBING"
HDL_TAP"TRUE";
"B \NAC \NWC"6;
"S \NAC"
BN"3"87;
%"TAP"
"1","(2175,1125)","2","standard","I118";
;
CDS_LIB"standard"
BODY_TYPE"PLUMBING"
HDL_TAP"TRUE";
"B \NAC \NWC"5;
"S \NAC"
BN"5"134;
%"TAP"
"1","(2175,1325)","2","standard","I119";
;
CDS_LIB"standard"
BODY_TYPE"PLUMBING"
HDL_TAP"TRUE";
"B \NAC \NWC"5;
"S \NAC"
BN"6"133;
%"TAP"
"1","(2425,975)","2","standard","I120";
;
CDS_LIB"standard"
BODY_TYPE"PLUMBING"
HDL_TAP"TRUE";
"B \NAC \NWC"6;
"S \NAC"
BN"4"89;
%"TAP"
"1","(2425,1175)","2","standard","I121";
;
CDS_LIB"standard"
BODY_TYPE"PLUMBING"
HDL_TAP"TRUE";
"B \NAC \NWC"6;
"S \NAC"
BN"5"127;
%"TAP"
"1","(2425,1375)","2","standard","I122";
;
CDS_LIB"standard"
BODY_TYPE"PLUMBING"
HDL_TAP"TRUE";
"B \NAC \NWC"6;
"S \NAC"
BN"6"128;
%"TAP"
"1","(2175,1525)","2","standard","I123";
;
CDS_LIB"standard"
BODY_TYPE"PLUMBING"
HDL_TAP"TRUE";
"B \NAC \NWC"5;
"S \NAC"
BN"7"135;
%"TAP"
"1","(2425,1575)","2","standard","I124";
;
CDS_LIB"standard"
BODY_TYPE"PLUMBING"
HDL_TAP"TRUE";
"B \NAC \NWC"6;
"S \NAC"
BN"7"129;
%"Q_CAP_DIFFBUS"
"2","(3150,175)","2","pure_quanta","I125";
;
PART_NUMBER"SP_CH4221MEE01"
VALUE"DIFF BUS_0.22UF"
$LOCATION"C708"
TOLERANCE"20%"
PACK_TYPE"C0201"
MATERIAL"X6S"
VOLTAGE"6.3V"
CDS_LMAN_SYM_OUTLINE"-25,50,25,-50"
CDS_LIB"pure_quanta"
PIN_NAMES_ROTATE"TRUE"
$LOCATION"C708"
CDS_LOCATION"C708"
$SEC"1"
CDS_SEC"1";
"2"
$PN"2"130;
"1"
$PN"1"84;
%"Q_CAP_DIFFBUS"
"2","(3150,125)","2","pure_quanta","I126";
;
PART_NUMBER"SP_CH4221MEE01"
VALUE"DIFF BUS_0.22UF"
$LOCATION"C709"
TOLERANCE"20%"
PACK_TYPE"C0201"
MATERIAL"X6S"
VOLTAGE"6.3V"
CDS_LMAN_SYM_OUTLINE"-25,50,25,-50"
CDS_LIB"pure_quanta"
PIN_NAMES_ROTATE"TRUE"
$LOCATION"C709"
CDS_LOCATION"C709"
$SEC"1"
CDS_SEC"1";
"2"
$PN"2"132;
"1"
$PN"1"83;
%"Q_CAP_DIFFBUS"
"2","(3150,375)","2","pure_quanta","I127";
;
PART_NUMBER"SP_CH4221MEE01"
VALUE"DIFF BUS_0.22UF"
$LOCATION"C706"
TOLERANCE"20%"
PACK_TYPE"C0201"
MATERIAL"X6S"
VOLTAGE"6.3V"
CDS_LIB"pure_quanta"
CDS_LMAN_SYM_OUTLINE"-25,50,25,-50"
PIN_NAMES_ROTATE"TRUE"
$LOCATION"C706"
CDS_LOCATION"C706"
$SEC"1"
CDS_SEC"1";
"2"
$PN"2"85;
"1"
$PN"1"119;
%"Q_CAP_DIFFBUS"
"2","(3150,325)","2","pure_quanta","I128";
;
PART_NUMBER"SP_CH4221MEE01"
VALUE"DIFF BUS_0.22UF"
$LOCATION"C707"
TOLERANCE"20%"
PACK_TYPE"C0201"
MATERIAL"X6S"
VOLTAGE"6.3V"
CDS_LMAN_SYM_OUTLINE"-25,50,25,-50"
CDS_LIB"pure_quanta"
PIN_NAMES_ROTATE"TRUE"
$LOCATION"C707"
CDS_LOCATION"C707"
$SEC"1"
CDS_SEC"1";
"2"
$PN"2"131;
"1"
$PN"1"126;
%"Q_CAP_DIFFBUS"
"2","(3150,575)","2","pure_quanta","I129";
;
PART_NUMBER"SP_CH4221MEE01"
VALUE"DIFF BUS_0.22UF"
$LOCATION"C704"
TOLERANCE"20%"
PACK_TYPE"C0201"
MATERIAL"X6S"
VOLTAGE"6.3V"
CDS_LMAN_SYM_OUTLINE"-25,50,25,-50"
CDS_LIB"pure_quanta"
PIN_NAMES_ROTATE"TRUE"
$LOCATION"C704"
CDS_LOCATION"C704"
$SEC"1"
CDS_SEC"1";
"2"
$PN"2"19;
"1"
$PN"1"120;
%"Q_CAP_DIFFBUS"
"2","(3150,525)","2","pure_quanta","I130";
;
PART_NUMBER"SP_CH4221MEE01"
VALUE"DIFF BUS_0.22UF"
$LOCATION"C705"
TOLERANCE"20%"
PACK_TYPE"C0201"
MATERIAL"X6S"
VOLTAGE"6.3V"
CDS_LMAN_SYM_OUTLINE"-25,50,25,-50"
CDS_LIB"pure_quanta"
PIN_NAMES_ROTATE"TRUE"
$LOCATION"C705"
CDS_LOCATION"C705"
$SEC"1"
CDS_SEC"1";
"2"
$PN"2"18;
"1"
$PN"1"123;
%"Q_CAP_DIFFBUS"
"2","(3150,925)","2","pure_quanta","I131";
;
PART_NUMBER"SP_CH4221MEE01"
VALUE"DIFF BUS_0.22UF"
$LOCATION"C701"
TOLERANCE"20%"
PACK_TYPE"C0201"
MATERIAL"X6S"
VOLTAGE"6.3V"
CDS_LMAN_SYM_OUTLINE"-25,50,25,-50"
CDS_LIB"pure_quanta"
PIN_NAMES_ROTATE"TRUE"
$LOCATION"C701"
CDS_LOCATION"C701"
$SEC"1"
CDS_SEC"1";
"2"
$PN"2"88;
"1"
$PN"1"122;
%"Q_CAP_DIFFBUS"
"2","(3150,775)","2","pure_quanta","I132";
;
PART_NUMBER"SP_CH4221MEE01"
VALUE"DIFF BUS_0.22UF"
$LOCATION"C702"
TOLERANCE"20%"
PACK_TYPE"C0201"
MATERIAL"X6S"
VOLTAGE"6.3V"
CDS_LIB"pure_quanta"
CDS_LMAN_SYM_OUTLINE"-25,50,25,-50"
PIN_NAMES_ROTATE"TRUE"
$LOCATION"C702"
CDS_LOCATION"C702"
$SEC"1"
CDS_SEC"1";
"2"
$PN"2"87;
"1"
$PN"1"121;
%"Q_CAP_DIFFBUS"
"2","(3150,725)","2","pure_quanta","I133";
;
PART_NUMBER"SP_CH4221MEE01"
VALUE"DIFF BUS_0.22UF"
$LOCATION"C703"
TOLERANCE"20%"
PACK_TYPE"C0201"
MATERIAL"X6S"
VOLTAGE"6.3V"
CDS_LIB"pure_quanta"
CDS_LMAN_SYM_OUTLINE"-25,50,25,-50"
PIN_NAMES_ROTATE"TRUE"
$LOCATION"C703"
CDS_LOCATION"C703"
$SEC"1"
CDS_SEC"1";
"2"
$PN"2"86;
"1"
$PN"1"124;
%"Q_CAP_DIFFBUS"
"2","(3150,975)","2","pure_quanta","I134";
;
PART_NUMBER"SP_CH4221MEE01"
VALUE"DIFF BUS_0.22UF"
$LOCATION"C700"
TOLERANCE"20%"
PACK_TYPE"C0201"
MATERIAL"X6S"
VOLTAGE"6.3V"
CDS_LMAN_SYM_OUTLINE"-25,50,25,-50"
CDS_LIB"pure_quanta"
PIN_NAMES_ROTATE"TRUE"
$LOCATION"C700"
CDS_LOCATION"C700"
$SEC"1"
CDS_SEC"1";
"2"
$PN"2"89;
"1"
$PN"1"125;
%"Q_CAP_DIFFBUS"
"2","(3150,1175)","2","pure_quanta","I135";
;
PART_NUMBER"SP_CH4221MEE01"
VALUE"DIFF BUS_0.22UF"
$LOCATION"C698"
TOLERANCE"20%"
PACK_TYPE"C0201"
MATERIAL"X6S"
VOLTAGE"6.3V"
CDS_LMAN_SYM_OUTLINE"-25,50,25,-50"
CDS_LIB"pure_quanta"
PIN_NAMES_ROTATE"TRUE"
$LOCATION"C698"
CDS_LOCATION"C698"
$SEC"1"
CDS_SEC"1";
"2"
$PN"2"127;
"1"
$PN"1"113;
%"Q_CAP_DIFFBUS"
"2","(3150,1125)","2","pure_quanta","I136";
;
PART_NUMBER"SP_CH4221MEE01"
VALUE"DIFF BUS_0.22UF"
$LOCATION"C699"
TOLERANCE"20%"
PACK_TYPE"C0201"
MATERIAL"X6S"
VOLTAGE"6.3V"
CDS_LMAN_SYM_OUTLINE"-25,50,25,-50"
CDS_LIB"pure_quanta"
PIN_NAMES_ROTATE"TRUE"
$LOCATION"C699"
CDS_LOCATION"C699"
$SEC"1"
CDS_SEC"1";
"2"
$PN"2"134;
"1"
$PN"1"116;
%"Q_CAP_DIFFBUS"
"2","(3150,1375)","2","pure_quanta","I137";
;
PART_NUMBER"SP_CH4221MEE01"
VALUE"DIFF BUS_0.22UF"
$LOCATION"C696"
TOLERANCE"20%"
PACK_TYPE"C0201"
MATERIAL"X6S"
VOLTAGE"6.3V"
CDS_LMAN_SYM_OUTLINE"-25,50,25,-50"
CDS_LIB"pure_quanta"
PIN_NAMES_ROTATE"TRUE"
$LOCATION"C696"
CDS_LOCATION"C696"
$SEC"1"
CDS_SEC"1";
"2"
$PN"2"128;
"1"
$PN"1"114;
%"Q_CAP_DIFFBUS"
"2","(3150,1325)","2","pure_quanta","I138";
;
PART_NUMBER"SP_CH4221MEE01"
VALUE"DIFF BUS_0.22UF"
$LOCATION"C697"
TOLERANCE"20%"
PACK_TYPE"C0201"
MATERIAL"X6S"
VOLTAGE"6.3V"
CDS_LMAN_SYM_OUTLINE"-25,50,25,-50"
CDS_LIB"pure_quanta"
PIN_NAMES_ROTATE"TRUE"
$LOCATION"C697"
CDS_LOCATION"C697"
$SEC"1"
CDS_SEC"1";
"2"
$PN"2"133;
"1"
$PN"1"118;
%"Q_CAP_DIFFBUS"
"2","(3150,1525)","2","pure_quanta","I139";
;
PART_NUMBER"SP_CH4221MEE01"
VALUE"DIFF BUS_0.22UF"
$LOCATION"C695"
TOLERANCE"20%"
PACK_TYPE"C0201"
MATERIAL"X6S"
VOLTAGE"6.3V"
CDS_LMAN_SYM_OUTLINE"-25,50,25,-50"
CDS_LIB"pure_quanta"
PIN_NAMES_ROTATE"TRUE"
$LOCATION"C695"
CDS_LOCATION"C695"
$SEC"1"
CDS_SEC"1";
"2"
$PN"2"135;
"1"
$PN"1"117;
%"Q_CAP_DIFFBUS"
"2","(3150,1575)","2","pure_quanta","I140";
;
PART_NUMBER"SP_CH4221MEE01"
VALUE"DIFF BUS_0.22UF"
$LOCATION"C694"
TOLERANCE"20%"
PACK_TYPE"C0201"
MATERIAL"X6S"
VOLTAGE"6.3V"
CDS_LIB"pure_quanta"
CDS_LMAN_SYM_OUTLINE"-25,50,25,-50"
PIN_NAMES_ROTATE"TRUE"
$LOCATION"C694"
CDS_LOCATION"C694"
$SEC"1"
CDS_SEC"1";
"2"
$PN"2"129;
"1"
$PN"1"115;
%"TAP"
"1","(2175,2100)","2","standard","I141";
;
CDS_LIB"standard"
BODY_TYPE"PLUMBING"
HDL_TAP"TRUE";
"B \NAC \NWC"3;
"S \NAC"
BN"8"136;
%"TAP"
"1","(2175,2300)","2","standard","I142";
;
CDS_LIB"standard"
BODY_TYPE"PLUMBING"
HDL_TAP"TRUE";
"B \NAC \NWC"3;
"S \NAC"
BN"9"108;
%"TAP"
"1","(2425,2150)","2","standard","I143";
;
CDS_LIB"standard"
BODY_TYPE"PLUMBING"
HDL_TAP"TRUE";
"B \NAC \NWC"1;
"S \NAC"
BN"8"137;
%"TAP"
"1","(2425,2350)","2","standard","I144";
;
CDS_LIB"standard"
BODY_TYPE"PLUMBING"
HDL_TAP"TRUE";
"B \NAC \NWC"1;
"S \NAC"
BN"9"106;
%"TAP"
"1","(2175,2700)","2","standard","I145";
;
CDS_LIB"standard"
BODY_TYPE"PLUMBING"
HDL_TAP"TRUE";
"B \NAC \NWC"3;
"S \NAC"
BN"11"109;
%"TAP"
"1","(2175,2500)","2","standard","I146";
;
CDS_LIB"standard"
BODY_TYPE"PLUMBING"
HDL_TAP"TRUE";
"B \NAC \NWC"3;
"S \NAC"
BN"10"141;
%"TAP"
"1","(2175,2900)","2","standard","I147";
;
CDS_LIB"standard"
BODY_TYPE"PLUMBING"
HDL_TAP"TRUE";
"B \NAC \NWC"3;
"S \NAC"
BN"12"107;
%"TAP"
"1","(2425,2550)","2","standard","I148";
;
CDS_LIB"standard"
BODY_TYPE"PLUMBING"
HDL_TAP"TRUE";
"B \NAC \NWC"1;
"S \NAC"
BN"10"140;
%"TAP"
"1","(2425,2750)","2","standard","I149";
;
CDS_LIB"standard"
BODY_TYPE"PLUMBING"
HDL_TAP"TRUE";
"B \NAC \NWC"1;
"S \NAC"
BN"11"144;
%"TAP"
"1","(2425,2950)","2","standard","I150";
;
CDS_LIB"standard"
BODY_TYPE"PLUMBING"
HDL_TAP"TRUE";
"B \NAC \NWC"1;
"S \NAC"
BN"12"142;
%"TAP"
"1","(2175,3100)","2","standard","I151";
;
CDS_LIB"standard"
BODY_TYPE"PLUMBING"
HDL_TAP"TRUE";
"B \NAC \NWC"3;
"S \NAC"
BN"13"110;
%"TAP"
"1","(2175,3500)","2","standard","I152";
;
CDS_LIB"standard"
BODY_TYPE"PLUMBING"
HDL_TAP"TRUE";
"B \NAC \NWC"3;
"S \NAC"
BN"15"111;
%"TAP"
"1","(2175,3300)","2","standard","I153";
;
CDS_LIB"standard"
BODY_TYPE"PLUMBING"
HDL_TAP"TRUE";
"B \NAC \NWC"3;
"S \NAC"
BN"14"112;
%"TAP"
"1","(2425,3150)","2","standard","I154";
;
CDS_LIB"standard"
BODY_TYPE"PLUMBING"
HDL_TAP"TRUE";
"B \NAC \NWC"1;
"S \NAC"
BN"13"104;
%"TAP"
"1","(2425,3350)","2","standard","I155";
;
CDS_LIB"standard"
BODY_TYPE"PLUMBING"
HDL_TAP"TRUE";
"B \NAC \NWC"1;
"S \NAC"
BN"14"105;
%"TAP"
"1","(2425,3550)","2","standard","I156";
;
CDS_LIB"standard"
BODY_TYPE"PLUMBING"
HDL_TAP"TRUE";
"B \NAC \NWC"1;
"S \NAC"
BN"15"103;
%"Q_CAP_DIFFBUS"
"2","(3150,2100)","2","pure_quanta","I157";
;
PART_NUMBER"SP_CH4221MEE01"
VALUE"DIFF BUS_0.22UF"
$LOCATION"C693"
TOLERANCE"20%"
PACK_TYPE"C0201"
MATERIAL"X6S"
VOLTAGE"6.3V"
PIN_NAMES_ROTATE"TRUE"
CDS_LIB"pure_quanta"
CDS_LMAN_SYM_OUTLINE"-25,50,25,-50"
$LOCATION"C693"
CDS_LOCATION"C693"
$SEC"1"
CDS_SEC"1";
"2"
$PN"2"136;
"1"
$PN"1"102;
%"Q_CAP_DIFFBUS"
"2","(3150,2150)","2","pure_quanta","I158";
;
PART_NUMBER"SP_CH4221MEE01"
VALUE"DIFF BUS_0.22UF"
$LOCATION"C692"
TOLERANCE"20%"
PACK_TYPE"C0201"
MATERIAL"X6S"
VOLTAGE"6.3V"
PIN_NAMES_ROTATE"TRUE"
CDS_LIB"pure_quanta"
CDS_LMAN_SYM_OUTLINE"-25,50,25,-50"
$LOCATION"C692"
CDS_LOCATION"C692"
$SEC"1"
CDS_SEC"1";
"2"
$PN"2"137;
"1"
$PN"1"97;
%"Q_CAP_DIFFBUS"
"2","(3150,2350)","2","pure_quanta","I159";
;
PART_NUMBER"SP_CH4221MEE01"
VALUE"DIFF BUS_0.22UF"
$LOCATION"C690"
TOLERANCE"20%"
PACK_TYPE"C0201"
MATERIAL"X6S"
VOLTAGE"6.3V"
PIN_NAMES_ROTATE"TRUE"
CDS_LMAN_SYM_OUTLINE"-25,50,25,-50"
CDS_LIB"pure_quanta"
$LOCATION"C690"
CDS_LOCATION"C690"
$SEC"1"
CDS_SEC"1";
"2"
$PN"2"106;
"1"
$PN"1"96;
%"Q_CAP_DIFFBUS"
"2","(3150,2300)","2","pure_quanta","I160";
;
PART_NUMBER"SP_CH4221MEE01"
VALUE"DIFF BUS_0.22UF"
$LOCATION"C691"
TOLERANCE"20%"
PACK_TYPE"C0201"
MATERIAL"X6S"
VOLTAGE"6.3V"
PIN_NAMES_ROTATE"TRUE"
CDS_LIB"pure_quanta"
CDS_LMAN_SYM_OUTLINE"-25,50,25,-50"
$LOCATION"C691"
CDS_LOCATION"C691"
$SEC"1"
CDS_SEC"1";
"2"
$PN"2"108;
"1"
$PN"1"138;
%"Q_CAP_DIFFBUS"
"2","(3150,2700)","2","pure_quanta","I161";
;
PART_NUMBER"SP_CH4221MEE01"
VALUE"DIFF BUS_0.22UF"
$LOCATION"C687"
TOLERANCE"20%"
PACK_TYPE"C0201"
MATERIAL"X6S"
VOLTAGE"6.3V"
PIN_NAMES_ROTATE"TRUE"
CDS_LMAN_SYM_OUTLINE"-25,50,25,-50"
CDS_LIB"pure_quanta"
$LOCATION"C687"
CDS_LOCATION"C687"
$SEC"1"
CDS_SEC"1";
"2"
$PN"2"109;
"1"
$PN"1"139;
%"Q_CAP_DIFFBUS"
"2","(3150,2550)","2","pure_quanta","I162";
;
PART_NUMBER"SP_CH4221MEE01"
VALUE"DIFF BUS_0.22UF"
$LOCATION"C688"
TOLERANCE"20%"
PACK_TYPE"C0201"
MATERIAL"X6S"
VOLTAGE"6.3V"
PIN_NAMES_ROTATE"TRUE"
CDS_LIB"pure_quanta"
CDS_LMAN_SYM_OUTLINE"-25,50,25,-50"
$LOCATION"C688"
CDS_LOCATION"C688"
$SEC"1"
CDS_SEC"1";
"2"
$PN"2"140;
"1"
$PN"1"98;
%"Q_CAP_DIFFBUS"
"2","(3150,2500)","2","pure_quanta","I163";
;
PART_NUMBER"SP_CH4221MEE01"
VALUE"DIFF BUS_0.22UF"
$LOCATION"C689"
TOLERANCE"20%"
PACK_TYPE"C0201"
MATERIAL"X6S"
VOLTAGE"6.3V"
PIN_NAMES_ROTATE"TRUE"
CDS_LIB"pure_quanta"
CDS_LMAN_SYM_OUTLINE"-25,50,25,-50"
$LOCATION"C689"
CDS_LOCATION"C689"
$SEC"1"
CDS_SEC"1";
"2"
$PN"2"141;
"1"
$PN"1"100;
%"Q_CAP_DIFFBUS"
"2","(3150,2750)","2","pure_quanta","I164";
;
PART_NUMBER"SP_CH4221MEE01"
VALUE"DIFF BUS_0.22UF"
$LOCATION"C686"
TOLERANCE"20%"
PACK_TYPE"C0201"
MATERIAL"X6S"
VOLTAGE"6.3V"
PIN_NAMES_ROTATE"TRUE"
CDS_LMAN_SYM_OUTLINE"-25,50,25,-50"
CDS_LIB"pure_quanta"
$LOCATION"C686"
CDS_LOCATION"C686"
$SEC"1"
CDS_SEC"1";
"2"
$PN"2"144;
"1"
$PN"1"143;
%"Q_CAP_DIFFBUS"
"2","(3150,2900)","2","pure_quanta","I165";
;
PART_NUMBER"SP_CH4221MEE01"
VALUE"DIFF BUS_0.22UF"
$LOCATION"C685"
TOLERANCE"20%"
PACK_TYPE"C0201"
MATERIAL"X6S"
VOLTAGE"6.3V"
PIN_NAMES_ROTATE"TRUE"
CDS_LIB"pure_quanta"
CDS_LMAN_SYM_OUTLINE"-25,50,25,-50"
$LOCATION"C685"
CDS_LOCATION"C685"
$SEC"1"
CDS_SEC"1";
"2"
$PN"2"107;
"1"
$PN"1"101;
%"Q_CAP_DIFFBUS"
"2","(3150,2950)","2","pure_quanta","I166";
;
PART_NUMBER"SP_CH4221MEE01"
VALUE"DIFF BUS_0.22UF"
$LOCATION"C684"
TOLERANCE"20%"
PACK_TYPE"C0201"
MATERIAL"X6S"
VOLTAGE"6.3V"
PIN_NAMES_ROTATE"TRUE"
CDS_LIB"pure_quanta"
CDS_LMAN_SYM_OUTLINE"-25,50,25,-50"
$LOCATION"C684"
CDS_LOCATION"C684"
$SEC"1"
CDS_SEC"1";
"2"
$PN"2"142;
"1"
$PN"1"99;
%"Q_CAP_DIFFBUS"
"2","(3150,3150)","2","pure_quanta","I167";
;
PART_NUMBER"SP_CH4221MEE01"
VALUE"DIFF BUS_0.22UF"
$LOCATION"C682"
TOLERANCE"20%"
PACK_TYPE"C0201"
MATERIAL"X6S"
VOLTAGE"6.3V"
PIN_NAMES_ROTATE"TRUE"
CDS_LIB"pure_quanta"
CDS_LMAN_SYM_OUTLINE"-25,50,25,-50"
$LOCATION"C682"
CDS_LOCATION"C682"
$SEC"1"
CDS_SEC"1";
"2"
$PN"2"104;
"1"
$PN"1"91;
%"Q_CAP_DIFFBUS"
"2","(3150,3100)","2","pure_quanta","I168";
;
PART_NUMBER"SP_CH4221MEE01"
VALUE"DIFF BUS_0.22UF"
$LOCATION"C683"
TOLERANCE"20%"
PACK_TYPE"C0201"
MATERIAL"X6S"
VOLTAGE"6.3V"
PIN_NAMES_ROTATE"TRUE"
CDS_LIB"pure_quanta"
CDS_LMAN_SYM_OUTLINE"-25,50,25,-50"
$LOCATION"C683"
CDS_LOCATION"C683"
$SEC"1"
CDS_SEC"1";
"2"
$PN"2"110;
"1"
$PN"1"95;
%"Q_CAP_DIFFBUS"
"2","(3150,3500)","2","pure_quanta","I169";
;
PART_NUMBER"SP_CH4221MEE01"
VALUE"DIFF BUS_0.22UF"
$LOCATION"C679"
TOLERANCE"20%"
PACK_TYPE"C0201"
MATERIAL"X6S"
VOLTAGE"6.3V"
PIN_NAMES_ROTATE"TRUE"
CDS_LIB"pure_quanta"
CDS_LMAN_SYM_OUTLINE"-25,50,25,-50"
$LOCATION"C679"
CDS_LOCATION"C679"
$SEC"1"
CDS_SEC"1";
"2"
$PN"2"111;
"1"
$PN"1"93;
%"Q_CAP_DIFFBUS"
"2","(3150,3350)","2","pure_quanta","I170";
;
PART_NUMBER"SP_CH4221MEE01"
VALUE"DIFF BUS_0.22UF"
$LOCATION"C680"
TOLERANCE"20%"
PACK_TYPE"C0201"
MATERIAL"X6S"
VOLTAGE"6.3V"
PIN_NAMES_ROTATE"TRUE"
CDS_LIB"pure_quanta"
CDS_LMAN_SYM_OUTLINE"-25,50,25,-50"
$LOCATION"C680"
CDS_LOCATION"C680"
$SEC"1"
CDS_SEC"1";
"2"
$PN"2"105;
"1"
$PN"1"90;
%"Q_CAP_DIFFBUS"
"2","(3150,3300)","2","pure_quanta","I171";
;
PART_NUMBER"SP_CH4221MEE01"
VALUE"DIFF BUS_0.22UF"
$LOCATION"C681"
TOLERANCE"20%"
PACK_TYPE"C0201"
MATERIAL"X6S"
VOLTAGE"6.3V"
PIN_NAMES_ROTATE"TRUE"
CDS_LIB"pure_quanta"
CDS_LMAN_SYM_OUTLINE"-25,50,25,-50"
$LOCATION"C681"
CDS_LOCATION"C681"
$SEC"1"
CDS_SEC"1";
"2"
$PN"2"112;
"1"
$PN"1"94;
%"Q_CAP_DIFFBUS"
"2","(3150,3550)","2","pure_quanta","I172";
;
PART_NUMBER"SP_CH4221MEE01"
TOLERANCE"20%"
VOLTAGE"6.3V"
PACK_TYPE"C0201"
MATERIAL"X6S"
VALUE"DIFF BUS_0.22UF"
$LOCATION"C678"
PIN_NAMES_ROTATE"TRUE"
CDS_LMAN_SYM_OUTLINE"-25,50,25,-50"
CDS_LIB"pure_quanta"
$LOCATION"C678"
CDS_LOCATION"C678"
$SEC"1"
CDS_SEC"1";
"2"
$PN"2"103;
"1"
$PN"1"92;
%"TAP"
"1","(3700,175)","0","standard","I173";
;
CDS_LIB"standard"
BODY_TYPE"PLUMBING"
HDL_TAP"TRUE";
"B \NAC \NWC"8;
"S \NAC"
BN"0"84;
%"TAP"
"1","(3900,125)","0","standard","I174";
;
CDS_LIB"standard"
BODY_TYPE"PLUMBING"
HDL_TAP"TRUE";
"B \NAC \NWC"7;
"S \NAC"
BN"0"83;
%"TAP"
"1","(3700,375)","0","standard","I175";
;
CDS_LIB"standard"
BODY_TYPE"PLUMBING"
HDL_TAP"TRUE";
"B \NAC \NWC"8;
"S \NAC"
BN"1"119;
%"TAP"
"1","(3900,325)","0","standard","I176";
;
CDS_LIB"standard"
BODY_TYPE"PLUMBING"
HDL_TAP"TRUE";
"B \NAC \NWC"7;
"S \NAC"
BN"1"126;
%"TAP"
"1","(3700,575)","0","standard","I177";
;
CDS_LIB"standard"
BODY_TYPE"PLUMBING"
HDL_TAP"TRUE";
"B \NAC \NWC"8;
"S \NAC"
BN"2"120;
%"TAP"
"1","(3900,525)","0","standard","I178";
;
CDS_LIB"standard"
BODY_TYPE"PLUMBING"
HDL_TAP"TRUE";
"B \NAC \NWC"7;
"S \NAC"
BN"2"123;
%"TAP"
"1","(3700,775)","0","standard","I179";
;
CDS_LIB"standard"
BODY_TYPE"PLUMBING"
HDL_TAP"TRUE";
"B \NAC \NWC"8;
"S \NAC"
BN"3"121;
%"TAP"
"1","(3900,725)","0","standard","I180";
;
CDS_LIB"standard"
BODY_TYPE"PLUMBING"
HDL_TAP"TRUE";
"B \NAC \NWC"7;
"S \NAC"
BN"3"124;
%"TAP"
"1","(3900,925)","0","standard","I181";
;
CDS_LIB"standard"
BODY_TYPE"PLUMBING"
HDL_TAP"TRUE";
"B \NAC \NWC"7;
"S \NAC"
BN"4"122;
%"TAP"
"1","(3700,1175)","0","standard","I182";
;
CDS_LIB"standard"
BODY_TYPE"PLUMBING"
HDL_TAP"TRUE";
"B \NAC \NWC"8;
"S \NAC"
BN"5"113;
%"TAP"
"1","(3700,975)","0","standard","I183";
;
CDS_LIB"standard"
BODY_TYPE"PLUMBING"
HDL_TAP"TRUE";
"B \NAC \NWC"8;
"S \NAC"
BN"4"125;
%"TAP"
"1","(3900,1125)","0","standard","I184";
;
CDS_LIB"standard"
BODY_TYPE"PLUMBING"
HDL_TAP"TRUE";
"B \NAC \NWC"7;
"S \NAC"
BN"5"116;
%"TAP"
"1","(3700,1375)","0","standard","I185";
;
CDS_LIB"standard"
BODY_TYPE"PLUMBING"
HDL_TAP"TRUE";
"B \NAC \NWC"8;
"S \NAC"
BN"6"114;
%"TAP"
"1","(3900,1325)","0","standard","I186";
;
CDS_LIB"standard"
BODY_TYPE"PLUMBING"
HDL_TAP"TRUE";
"B \NAC \NWC"7;
"S \NAC"
BN"6"118;
%"TAP"
"1","(3900,1525)","0","standard","I187";
;
CDS_LIB"standard"
BODY_TYPE"PLUMBING"
HDL_TAP"TRUE";
"B \NAC \NWC"7;
"S \NAC"
BN"7"117;
%"TAP"
"1","(3700,1575)","0","standard","I188";
;
CDS_LIB"standard"
BODY_TYPE"PLUMBING"
HDL_TAP"TRUE";
"B \NAC \NWC"8;
"S \NAC"
BN"7"115;
%"TAP"
"1","(3700,2150)","0","standard","I191";
;
CDS_LIB"standard"
BODY_TYPE"PLUMBING"
HDL_TAP"TRUE";
"B \NAC \NWC"2;
"S \NAC"
BN"8"97;
%"TAP"
"1","(3900,2100)","0","standard","I192";
;
CDS_LIB"standard"
BODY_TYPE"PLUMBING"
HDL_TAP"TRUE";
"B \NAC \NWC"4;
"S \NAC"
BN"8"102;
%"TAP"
"1","(3900,2300)","0","standard","I193";
;
CDS_LIB"standard"
BODY_TYPE"PLUMBING"
HDL_TAP"TRUE";
"B \NAC \NWC"4;
"S \NAC"
BN"9"138;
%"TAP"
"1","(3700,2350)","0","standard","I194";
;
CDS_LIB"standard"
BODY_TYPE"PLUMBING"
HDL_TAP"TRUE";
"B \NAC \NWC"2;
"S \NAC"
BN"9"96;
%"TAP"
"1","(3700,2550)","0","standard","I195";
;
CDS_LIB"standard"
BODY_TYPE"PLUMBING"
HDL_TAP"TRUE";
"B \NAC \NWC"2;
"S \NAC"
BN"10"98;
%"TAP"
"1","(3900,2700)","0","standard","I196";
;
CDS_LIB"standard"
BODY_TYPE"PLUMBING"
HDL_TAP"TRUE";
"B \NAC \NWC"4;
"S \NAC"
BN"11"139;
%"TAP"
"1","(3900,2500)","0","standard","I197";
;
CDS_LIB"standard"
BODY_TYPE"PLUMBING"
HDL_TAP"TRUE";
"B \NAC \NWC"4;
"S \NAC"
BN"10"100;
%"TAP"
"1","(3700,2950)","0","standard","I198";
;
CDS_LIB"standard"
BODY_TYPE"PLUMBING"
HDL_TAP"TRUE";
"B \NAC \NWC"2;
"S \NAC"
BN"12"99;
%"TAP"
"1","(3700,2750)","0","standard","I199";
;
CDS_LIB"standard"
BODY_TYPE"PLUMBING"
HDL_TAP"TRUE";
"B \NAC \NWC"2;
"S \NAC"
BN"11"143;
%"TAP"
"1","(3900,2900)","0","standard","I200";
;
CDS_LIB"standard"
BODY_TYPE"PLUMBING"
HDL_TAP"TRUE";
"B \NAC \NWC"4;
"S \NAC"
BN"12"101;
%"TAP"
"1","(3700,3150)","0","standard","I201";
;
CDS_LIB"standard"
BODY_TYPE"PLUMBING"
HDL_TAP"TRUE";
"B \NAC \NWC"2;
"S \NAC"
BN"13"91;
%"TAP"
"1","(3900,3100)","0","standard","I202";
;
CDS_LIB"standard"
BODY_TYPE"PLUMBING"
HDL_TAP"TRUE";
"B \NAC \NWC"4;
"S \NAC"
BN"13"95;
%"TAP"
"1","(3700,3350)","0","standard","I203";
;
CDS_LIB"standard"
BODY_TYPE"PLUMBING"
HDL_TAP"TRUE";
"B \NAC \NWC"2;
"S \NAC"
BN"14"90;
%"TAP"
"1","(3900,3300)","0","standard","I204";
;
CDS_LIB"standard"
BODY_TYPE"PLUMBING"
HDL_TAP"TRUE";
"B \NAC \NWC"4;
"S \NAC"
BN"14"94;
%"TAP"
"1","(3900,3500)","0","standard","I205";
;
CDS_LIB"standard"
BODY_TYPE"PLUMBING"
HDL_TAP"TRUE";
"B \NAC \NWC"4;
"S \NAC"
BN"15"93;
%"TAP"
"1","(3700,3550)","0","standard","I206";
;
CDS_LIB"standard"
BODY_TYPE"PLUMBING"
HDL_TAP"TRUE";
"B \NAC \NWC"2;
"S \NAC"
BN"15"92;
%"TAP"
"1","(-2450,125)","2","standard","I213";
;
CDS_LIB"standard"
BODY_TYPE"PLUMBING"
HDL_TAP"TRUE";
"B \NAC \NWC"9;
"S \NAC"
BN"0"82;
%"TAP"
"1","(-2450,325)","2","standard","I214";
;
CDS_LIB"standard"
BODY_TYPE"PLUMBING"
HDL_TAP"TRUE";
"B \NAC \NWC"9;
"S \NAC"
BN"1"36;
%"TAP"
"1","(-2200,175)","2","standard","I215";
;
CDS_LIB"standard"
BODY_TYPE"PLUMBING"
HDL_TAP"TRUE";
"B \NAC \NWC"10;
"S \NAC"
BN"0"81;
%"TAP"
"1","(-2200,375)","2","standard","I216";
;
CDS_LIB"standard"
BODY_TYPE"PLUMBING"
HDL_TAP"TRUE";
"B \NAC \NWC"10;
"S \NAC"
BN"1"80;
%"TAP"
"1","(-2450,525)","2","standard","I217";
;
CDS_LIB"standard"
BODY_TYPE"PLUMBING"
HDL_TAP"TRUE";
"B \NAC \NWC"9;
"S \NAC"
BN"2"78;
%"TAP"
"1","(-2450,725)","2","standard","I218";
;
CDS_LIB"standard"
BODY_TYPE"PLUMBING"
HDL_TAP"TRUE";
"B \NAC \NWC"9;
"S \NAC"
BN"3"56;
%"TAP"
"1","(-2450,925)","2","standard","I219";
;
CDS_LIB"standard"
BODY_TYPE"PLUMBING"
HDL_TAP"TRUE";
"B \NAC \NWC"9;
"S \NAC"
BN"4"53;
%"TAP"
"1","(-2200,575)","2","standard","I220";
;
CDS_LIB"standard"
BODY_TYPE"PLUMBING"
HDL_TAP"TRUE";
"B \NAC \NWC"10;
"S \NAC"
BN"2"79;
%"TAP"
"1","(-2200,775)","2","standard","I221";
;
CDS_LIB"standard"
BODY_TYPE"PLUMBING"
HDL_TAP"TRUE";
"B \NAC \NWC"10;
"S \NAC"
BN"3"58;
%"TAP"
"1","(-2200,975)","2","standard","I222";
;
CDS_LIB"standard"
BODY_TYPE"PLUMBING"
HDL_TAP"TRUE";
"B \NAC \NWC"10;
"S \NAC"
BN"4"57;
%"TAP"
"1","(-2450,1125)","2","standard","I223";
;
CDS_LIB"standard"
BODY_TYPE"PLUMBING"
HDL_TAP"TRUE";
"B \NAC \NWC"9;
"S \NAC"
BN"5"33;
%"TAP"
"1","(-2450,1325)","2","standard","I224";
;
CDS_LIB"standard"
BODY_TYPE"PLUMBING"
HDL_TAP"TRUE";
"B \NAC \NWC"9;
"S \NAC"
BN"6"55;
%"TAP"
"1","(-2200,1175)","2","standard","I225";
;
CDS_LIB"standard"
BODY_TYPE"PLUMBING"
HDL_TAP"TRUE";
"B \NAC \NWC"10;
"S \NAC"
BN"5"61;
%"TAP"
"1","(-2200,1375)","2","standard","I226";
;
CDS_LIB"standard"
BODY_TYPE"PLUMBING"
HDL_TAP"TRUE";
"B \NAC \NWC"10;
"S \NAC"
BN"6"60;
%"TAP"
"1","(-2450,1525)","2","standard","I227";
;
CDS_LIB"standard"
BODY_TYPE"PLUMBING"
HDL_TAP"TRUE";
"B \NAC \NWC"9;
"S \NAC"
BN"7"54;
%"TAP"
"1","(-2200,1575)","2","standard","I228";
;
CDS_LIB"standard"
BODY_TYPE"PLUMBING"
HDL_TAP"TRUE";
"B \NAC \NWC"10;
"S \NAC"
BN"7"59;
%"Q_CAP_DIFFBUS"
"2","(-1475,125)","2","pure_quanta","I229";
;
PART_NUMBER"SP_CH4221MEE01"
VALUE"DIFF BUS_0.22UF"
$LOCATION"C1547"
TOLERANCE"20%"
PACK_TYPE"C0201"
MATERIAL"X6S"
VOLTAGE"6.3V"
CDS_LMAN_SYM_OUTLINE"-25,50,25,-50"
CDS_LIB"pure_quanta"
PIN_NAMES_ROTATE"TRUE"
CDS_LOCATION"C1547"
$SEC"1"
CDS_SEC"1";
"2"
$PN"2"82;
"1"
$PN"1"26;
%"Q_CAP_DIFFBUS"
"2","(-1475,175)","2","pure_quanta","I230";
;
PART_NUMBER"SP_CH4221MEE01"
VALUE"DIFF BUS_0.22UF"
$LOCATION"C1546"
TOLERANCE"20%"
PACK_TYPE"C0201"
MATERIAL"X6S"
VOLTAGE"6.3V"
CDS_LMAN_SYM_OUTLINE"-25,50,25,-50"
CDS_LIB"pure_quanta"
PIN_NAMES_ROTATE"TRUE"
CDS_LOCATION"C1546"
$SEC"1"
CDS_SEC"1";
"2"
$PN"2"81;
"1"
$PN"1"77;
%"Q_CAP_DIFFBUS"
"2","(-1475,325)","2","pure_quanta","I231";
;
PART_NUMBER"SP_CH4221MEE01"
VALUE"DIFF BUS_0.22UF"
$LOCATION"C1545"
TOLERANCE"20%"
PACK_TYPE"C0201"
MATERIAL"X6S"
VOLTAGE"6.3V"
CDS_LMAN_SYM_OUTLINE"-25,50,25,-50"
CDS_LIB"pure_quanta"
PIN_NAMES_ROTATE"TRUE"
CDS_LOCATION"C1545"
$SEC"1"
CDS_SEC"1";
"2"
$PN"2"36;
"1"
$PN"1"27;
%"Q_CAP_DIFFBUS"
"2","(-1475,375)","2","pure_quanta","I232";
;
PART_NUMBER"SP_CH4221MEE01"
VALUE"DIFF BUS_0.22UF"
$LOCATION"C1544"
TOLERANCE"20%"
PACK_TYPE"C0201"
MATERIAL"X6S"
VOLTAGE"6.3V"
CDS_LIB"pure_quanta"
CDS_LMAN_SYM_OUTLINE"-25,50,25,-50"
PIN_NAMES_ROTATE"TRUE"
CDS_LOCATION"C1544"
$SEC"1"
CDS_SEC"1";
"2"
$PN"2"80;
"1"
$PN"1"28;
%"Q_CAP_DIFFBUS"
"2","(-1475,575)","2","pure_quanta","I233";
;
PART_NUMBER"SP_CH4221MEE01"
VALUE"DIFF BUS_0.22UF"
$LOCATION"C1542"
TOLERANCE"20%"
PACK_TYPE"C0201"
MATERIAL"X6S"
VOLTAGE"6.3V"
CDS_LMAN_SYM_OUTLINE"-25,50,25,-50"
CDS_LIB"pure_quanta"
PIN_NAMES_ROTATE"TRUE"
CDS_LOCATION"C1542"
$SEC"1"
CDS_SEC"1";
"2"
$PN"2"79;
"1"
$PN"1"35;
%"Q_CAP_DIFFBUS"
"2","(-1475,525)","2","pure_quanta","I234";
;
PART_NUMBER"SP_CH4221MEE01"
VALUE"DIFF BUS_0.22UF"
$LOCATION"C1543"
TOLERANCE"20%"
PACK_TYPE"C0201"
MATERIAL"X6S"
VOLTAGE"6.3V"
CDS_LMAN_SYM_OUTLINE"-25,50,25,-50"
CDS_LIB"pure_quanta"
PIN_NAMES_ROTATE"TRUE"
CDS_LOCATION"C1543"
$SEC"1"
CDS_SEC"1";
"2"
$PN"2"78;
"1"
$PN"1"29;
%"Q_CAP_DIFFBUS"
"2","(-1475,725)","2","pure_quanta","I235";
;
PART_NUMBER"SP_CH4221MEE01"
VALUE"DIFF BUS_0.22UF"
$LOCATION"C1541"
TOLERANCE"20%"
PACK_TYPE"C0201"
MATERIAL"X6S"
VOLTAGE"6.3V"
CDS_LIB"pure_quanta"
CDS_LMAN_SYM_OUTLINE"-25,50,25,-50"
PIN_NAMES_ROTATE"TRUE"
CDS_LOCATION"C1541"
$SEC"1"
CDS_SEC"1";
"2"
$PN"2"56;
"1"
$PN"1"30;
%"Q_CAP_DIFFBUS"
"2","(-1475,775)","2","pure_quanta","I236";
;
PART_NUMBER"SP_CH4221MEE01"
VALUE"DIFF BUS_0.22UF"
$LOCATION"C1540"
TOLERANCE"20%"
PACK_TYPE"C0201"
MATERIAL"X6S"
VOLTAGE"6.3V"
CDS_LIB"pure_quanta"
CDS_LMAN_SYM_OUTLINE"-25,50,25,-50"
PIN_NAMES_ROTATE"TRUE"
CDS_LOCATION"C1540"
$SEC"1"
CDS_SEC"1";
"2"
$PN"2"58;
"1"
$PN"1"34;
%"Q_CAP_DIFFBUS"
"2","(-1475,925)","2","pure_quanta","I237";
;
PART_NUMBER"SP_CH4221MEE01"
VALUE"DIFF BUS_0.22UF"
$LOCATION"C1539"
TOLERANCE"20%"
PACK_TYPE"C0201"
MATERIAL"X6S"
VOLTAGE"6.3V"
CDS_LMAN_SYM_OUTLINE"-25,50,25,-50"
CDS_LIB"pure_quanta"
PIN_NAMES_ROTATE"TRUE"
CDS_LOCATION"C1539"
$SEC"1"
CDS_SEC"1";
"2"
$PN"2"53;
"1"
$PN"1"31;
%"Q_CAP_DIFFBUS"
"2","(-1475,975)","2","pure_quanta","I238";
;
PART_NUMBER"SP_CH4221MEE01"
VALUE"DIFF BUS_0.22UF"
$LOCATION"C1538"
TOLERANCE"20%"
PACK_TYPE"C0201"
MATERIAL"X6S"
VOLTAGE"6.3V"
CDS_LMAN_SYM_OUTLINE"-25,50,25,-50"
CDS_LIB"pure_quanta"
PIN_NAMES_ROTATE"TRUE"
CDS_LOCATION"C1538"
$SEC"1"
CDS_SEC"1";
"2"
$PN"2"57;
"1"
$PN"1"17;
%"TAP"
"1","(-925,175)","0","standard","I239";
;
CDS_LIB"standard"
BODY_TYPE"PLUMBING"
HDL_TAP"TRUE";
"B \NAC \NWC"11;
"S \NAC"
BN"0"77;
%"TAP"
"1","(-925,375)","0","standard","I240";
;
CDS_LIB"standard"
BODY_TYPE"PLUMBING"
HDL_TAP"TRUE";
"B \NAC \NWC"11;
"S \NAC"
BN"1"28;
%"TAP"
"1","(-725,125)","0","standard","I241";
;
CDS_LIB"standard"
BODY_TYPE"PLUMBING"
HDL_TAP"TRUE";
"B \NAC \NWC"14;
"S \NAC"
BN"0"26;
%"TAP"
"1","(-725,325)","0","standard","I242";
;
CDS_LIB"standard"
BODY_TYPE"PLUMBING"
HDL_TAP"TRUE";
"B \NAC \NWC"14;
"S \NAC"
BN"1"27;
%"TAP"
"1","(-925,575)","0","standard","I243";
;
CDS_LIB"standard"
BODY_TYPE"PLUMBING"
HDL_TAP"TRUE";
"B \NAC \NWC"11;
"S \NAC"
BN"2"35;
%"TAP"
"1","(-925,975)","0","standard","I244";
;
CDS_LIB"standard"
BODY_TYPE"PLUMBING"
HDL_TAP"TRUE";
"B \NAC \NWC"11;
"S \NAC"
BN"4"17;
%"TAP"
"1","(-925,775)","0","standard","I245";
;
CDS_LIB"standard"
BODY_TYPE"PLUMBING"
HDL_TAP"TRUE";
"B \NAC \NWC"11;
"S \NAC"
BN"3"34;
%"TAP"
"1","(-725,725)","0","standard","I246";
;
CDS_LIB"standard"
BODY_TYPE"PLUMBING"
HDL_TAP"TRUE";
"B \NAC \NWC"14;
"S \NAC"
BN"3"30;
%"TAP"
"1","(-725,525)","0","standard","I247";
;
CDS_LIB"standard"
BODY_TYPE"PLUMBING"
HDL_TAP"TRUE";
"B \NAC \NWC"14;
"S \NAC"
BN"2"29;
%"TAP"
"1","(-725,925)","0","standard","I248";
;
CDS_LIB"standard"
BODY_TYPE"PLUMBING"
HDL_TAP"TRUE";
"B \NAC \NWC"14;
"S \NAC"
BN"4"31;
%"Q_CAP_DIFFBUS"
"2","(-1475,1125)","2","pure_quanta","I249";
;
PART_NUMBER"SP_CH4221MEE01"
VALUE"DIFF BUS_0.22UF"
$LOCATION"C1537"
TOLERANCE"20%"
PACK_TYPE"C0201"
MATERIAL"X6S"
VOLTAGE"6.3V"
CDS_LMAN_SYM_OUTLINE"-25,50,25,-50"
CDS_LIB"pure_quanta"
PIN_NAMES_ROTATE"TRUE"
CDS_LOCATION"C1537"
$SEC"1"
CDS_SEC"1";
"2"
$PN"2"33;
"1"
$PN"1"38;
%"Q_CAP_DIFFBUS"
"2","(-1475,1175)","2","pure_quanta","I250";
;
PART_NUMBER"SP_CH4221MEE01"
VALUE"DIFF BUS_0.22UF"
$LOCATION"C1536"
TOLERANCE"20%"
PACK_TYPE"C0201"
MATERIAL"X6S"
VOLTAGE"6.3V"
CDS_LMAN_SYM_OUTLINE"-25,50,25,-50"
CDS_LIB"pure_quanta"
PIN_NAMES_ROTATE"TRUE"
CDS_LOCATION"C1536"
$SEC"1"
CDS_SEC"1";
"2"
$PN"2"61;
"1"
$PN"1"37;
%"Q_CAP_DIFFBUS"
"2","(-1475,1375)","2","pure_quanta","I251";
;
PART_NUMBER"SP_CH4221MEE01"
VALUE"DIFF BUS_0.22UF"
$LOCATION"C1534"
TOLERANCE"20%"
PACK_TYPE"C0201"
MATERIAL"X6S"
VOLTAGE"6.3V"
CDS_LMAN_SYM_OUTLINE"-25,50,25,-50"
CDS_LIB"pure_quanta"
PIN_NAMES_ROTATE"TRUE"
CDS_LOCATION"C1534"
$SEC"1"
CDS_SEC"1";
"2"
$PN"2"60;
"1"
$PN"1"52;
%"Q_CAP_DIFFBUS"
"2","(-1475,1325)","2","pure_quanta","I252";
;
PART_NUMBER"SP_CH4221MEE01"
VALUE"DIFF BUS_0.22UF"
$LOCATION"C1535"
TOLERANCE"20%"
PACK_TYPE"C0201"
MATERIAL"X6S"
VOLTAGE"6.3V"
CDS_LMAN_SYM_OUTLINE"-25,50,25,-50"
CDS_LIB"pure_quanta"
PIN_NAMES_ROTATE"TRUE"
CDS_LOCATION"C1535"
$SEC"1"
CDS_SEC"1";
"2"
$PN"2"55;
"1"
$PN"1"20;
%"Q_CAP_DIFFBUS"
"2","(-1475,1525)","2","pure_quanta","I253";
;
PART_NUMBER"SP_CH4221MEE01"
VALUE"DIFF BUS_0.22UF"
$LOCATION"C1533"
TOLERANCE"20%"
PACK_TYPE"C0201"
MATERIAL"X6S"
VOLTAGE"6.3V"
CDS_LMAN_SYM_OUTLINE"-25,50,25,-50"
CDS_LIB"pure_quanta"
PIN_NAMES_ROTATE"TRUE"
CDS_LOCATION"C1533"
$SEC"1"
CDS_SEC"1";
"2"
$PN"2"54;
"1"
$PN"1"50;
%"Q_CAP_DIFFBUS"
"2","(-1475,1575)","2","pure_quanta","I254";
;
PART_NUMBER"SP_CH4221MEE01"
VALUE"DIFF BUS_0.22UF"
$LOCATION"C1532"
TOLERANCE"20%"
PACK_TYPE"C0201"
MATERIAL"X6S"
VOLTAGE"6.3V"
CDS_LIB"pure_quanta"
CDS_LMAN_SYM_OUTLINE"-25,50,25,-50"
PIN_NAMES_ROTATE"TRUE"
CDS_LOCATION"C1532"
$SEC"1"
CDS_SEC"1";
"2"
$PN"2"59;
"1"
$PN"1"51;
%"TAP"
"1","(-925,1175)","0","standard","I255";
;
CDS_LIB"standard"
BODY_TYPE"PLUMBING"
HDL_TAP"TRUE";
"B \NAC \NWC"11;
"S \NAC"
BN"5"37;
%"TAP"
"1","(-925,1375)","0","standard","I256";
;
CDS_LIB"standard"
BODY_TYPE"PLUMBING"
HDL_TAP"TRUE";
"B \NAC \NWC"11;
"S \NAC"
BN"6"52;
%"TAP"
"1","(-725,1125)","0","standard","I257";
;
CDS_LIB"standard"
BODY_TYPE"PLUMBING"
HDL_TAP"TRUE";
"B \NAC \NWC"14;
"S \NAC"
BN"5"38;
%"TAP"
"1","(-725,1325)","0","standard","I258";
;
CDS_LIB"standard"
BODY_TYPE"PLUMBING"
HDL_TAP"TRUE";
"B \NAC \NWC"14;
"S \NAC"
BN"6"20;
%"TAP"
"1","(-925,1575)","0","standard","I259";
;
CDS_LIB"standard"
BODY_TYPE"PLUMBING"
HDL_TAP"TRUE";
"B \NAC \NWC"11;
"S \NAC"
BN"7"51;
%"TAP"
"1","(-725,1525)","0","standard","I260";
;
CDS_LIB"standard"
BODY_TYPE"PLUMBING"
HDL_TAP"TRUE";
"B \NAC \NWC"14;
"S \NAC"
BN"7"50;
%"TAP"
"1","(-2450,2100)","2","standard","I261";
;
CDS_LIB"standard"
BODY_TYPE"PLUMBING"
HDL_TAP"TRUE";
"B \NAC \NWC"12;
"S \NAC"
BN"8"65;
%"TAP"
"1","(-2450,2500)","2","standard","I262";
;
CDS_LIB"standard"
BODY_TYPE"PLUMBING"
HDL_TAP"TRUE";
"B \NAC \NWC"12;
"S \NAC"
BN"10"69;
%"TAP"
"1","(-2450,2300)","2","standard","I263";
;
CDS_LIB"standard"
BODY_TYPE"PLUMBING"
HDL_TAP"TRUE";
"B \NAC \NWC"12;
"S \NAC"
BN"9"67;
%"TAP"
"1","(-2200,2150)","2","standard","I264";
;
CDS_LIB"standard"
BODY_TYPE"PLUMBING"
HDL_TAP"TRUE";
"B \NAC \NWC"13;
"S \NAC"
BN"8"70;
%"TAP"
"1","(-2200,2350)","2","standard","I265";
;
CDS_LIB"standard"
BODY_TYPE"PLUMBING"
HDL_TAP"TRUE";
"B \NAC \NWC"13;
"S \NAC"
BN"9"71;
%"TAP"
"1","(-2450,2700)","2","standard","I266";
;
CDS_LIB"standard"
BODY_TYPE"PLUMBING"
HDL_TAP"TRUE";
"B \NAC \NWC"12;
"S \NAC"
BN"11"66;
%"TAP"
"1","(-2450,2900)","2","standard","I267";
;
CDS_LIB"standard"
BODY_TYPE"PLUMBING"
HDL_TAP"TRUE";
"B \NAC \NWC"12;
"S \NAC"
BN"12"68;
%"TAP"
"1","(-2200,2750)","2","standard","I268";
;
CDS_LIB"standard"
BODY_TYPE"PLUMBING"
HDL_TAP"TRUE";
"B \NAC \NWC"13;
"S \NAC"
BN"11"62;
%"TAP"
"1","(-2200,2550)","2","standard","I269";
;
CDS_LIB"standard"
BODY_TYPE"PLUMBING"
HDL_TAP"TRUE";
"B \NAC \NWC"13;
"S \NAC"
BN"10"72;
%"TAP"
"1","(-2200,2950)","2","standard","I270";
;
CDS_LIB"standard"
BODY_TYPE"PLUMBING"
HDL_TAP"TRUE";
"B \NAC \NWC"13;
"S \NAC"
BN"12"21;
%"TAP"
"1","(-2450,3100)","2","standard","I271";
;
CDS_LIB"standard"
BODY_TYPE"PLUMBING"
HDL_TAP"TRUE";
"B \NAC \NWC"12;
"S \NAC"
BN"13"76;
%"TAP"
"1","(-2450,3300)","2","standard","I272";
;
CDS_LIB"standard"
BODY_TYPE"PLUMBING"
HDL_TAP"TRUE";
"B \NAC \NWC"12;
"S \NAC"
BN"14"63;
%"TAP"
"1","(-2450,3500)","2","standard","I273";
;
CDS_LIB"standard"
BODY_TYPE"PLUMBING"
HDL_TAP"TRUE";
"B \NAC \NWC"12;
"S \NAC"
BN"15"64;
%"TAP"
"1","(-2200,3150)","2","standard","I274";
;
CDS_LIB"standard"
BODY_TYPE"PLUMBING"
HDL_TAP"TRUE";
"B \NAC \NWC"13;
"S \NAC"
BN"13"74;
%"TAP"
"1","(-2200,3350)","2","standard","I275";
;
CDS_LIB"standard"
BODY_TYPE"PLUMBING"
HDL_TAP"TRUE";
"B \NAC \NWC"13;
"S \NAC"
BN"14"73;
%"TAP"
"1","(-2200,3550)","2","standard","I276";
;
CDS_LIB"standard"
BODY_TYPE"PLUMBING"
HDL_TAP"TRUE";
"B \NAC \NWC"13;
"S \NAC"
BN"15"75;
%"Q_CAP_DIFFBUS"
"2","(-1475,2150)","2","pure_quanta","I277";
;
PART_NUMBER"SP_CH4221MEE01"
VALUE"DIFF BUS_0.22UF"
$LOCATION"C1530"
TOLERANCE"20%"
PACK_TYPE"C0201"
MATERIAL"X6S"
VOLTAGE"6.3V"
PIN_NAMES_ROTATE"TRUE"
CDS_LIB"pure_quanta"
CDS_LMAN_SYM_OUTLINE"-25,50,25,-50"
CDS_LOCATION"C1530"
$SEC"1"
CDS_SEC"1";
"2"
$PN"2"70;
"1"
$PN"1"46;
%"Q_CAP_DIFFBUS"
"2","(-1475,2100)","2","pure_quanta","I278";
;
PART_NUMBER"SP_CH4221MEE01"
VALUE"DIFF BUS_0.22UF"
$LOCATION"C1531"
TOLERANCE"20%"
PACK_TYPE"C0201"
MATERIAL"X6S"
VOLTAGE"6.3V"
PIN_NAMES_ROTATE"TRUE"
CDS_LIB"pure_quanta"
CDS_LMAN_SYM_OUTLINE"-25,50,25,-50"
CDS_LOCATION"C1531"
$SEC"1"
CDS_SEC"1";
"2"
$PN"2"65;
"1"
$PN"1"32;
%"Q_CAP_DIFFBUS"
"2","(-1475,2300)","2","pure_quanta","I279";
;
PART_NUMBER"SP_CH4221MEE01"
VALUE"DIFF BUS_0.22UF"
$LOCATION"C1529"
TOLERANCE"20%"
PACK_TYPE"C0201"
MATERIAL"X6S"
VOLTAGE"6.3V"
PIN_NAMES_ROTATE"TRUE"
CDS_LIB"pure_quanta"
CDS_LMAN_SYM_OUTLINE"-25,50,25,-50"
CDS_LOCATION"C1529"
$SEC"1"
CDS_SEC"1";
"2"
$PN"2"67;
"1"
$PN"1"42;
%"Q_CAP_DIFFBUS"
"2","(-1475,2350)","2","pure_quanta","I280";
;
PART_NUMBER"SP_CH4221MEE01"
VALUE"DIFF BUS_0.22UF"
$LOCATION"C1528"
TOLERANCE"20%"
PACK_TYPE"C0201"
MATERIAL"X6S"
VOLTAGE"6.3V"
PIN_NAMES_ROTATE"TRUE"
CDS_LMAN_SYM_OUTLINE"-25,50,25,-50"
CDS_LIB"pure_quanta"
CDS_LOCATION"C1528"
$SEC"1"
CDS_SEC"1";
"2"
$PN"2"71;
"1"
$PN"1"47;
%"Q_CAP_DIFFBUS"
"2","(-1475,2500)","2","pure_quanta","I281";
;
PART_NUMBER"SP_CH4221MEE01"
VALUE"DIFF BUS_0.22UF"
$LOCATION"C1527"
TOLERANCE"20%"
PACK_TYPE"C0201"
MATERIAL"X6S"
VOLTAGE"6.3V"
PIN_NAMES_ROTATE"TRUE"
CDS_LIB"pure_quanta"
CDS_LMAN_SYM_OUTLINE"-25,50,25,-50"
CDS_LOCATION"C1527"
$SEC"1"
CDS_SEC"1";
"2"
$PN"2"69;
"1"
$PN"1"41;
%"Q_CAP_DIFFBUS"
"2","(-1475,2550)","2","pure_quanta","I282";
;
PART_NUMBER"SP_CH4221MEE01"
VALUE"DIFF BUS_0.22UF"
$LOCATION"C1526"
TOLERANCE"20%"
PACK_TYPE"C0201"
MATERIAL"X6S"
VOLTAGE"6.3V"
PIN_NAMES_ROTATE"TRUE"
CDS_LIB"pure_quanta"
CDS_LMAN_SYM_OUTLINE"-25,50,25,-50"
CDS_LOCATION"C1526"
$SEC"1"
CDS_SEC"1";
"2"
$PN"2"72;
"1"
$PN"1"45;
%"Q_CAP_DIFFBUS"
"2","(-1475,2700)","2","pure_quanta","I283";
;
PART_NUMBER"SP_CH4221MEE01"
VALUE"DIFF BUS_0.22UF"
$LOCATION"C1525"
TOLERANCE"20%"
PACK_TYPE"C0201"
MATERIAL"X6S"
VOLTAGE"6.3V"
PIN_NAMES_ROTATE"TRUE"
CDS_LMAN_SYM_OUTLINE"-25,50,25,-50"
CDS_LIB"pure_quanta"
CDS_LOCATION"C1525"
$SEC"1"
CDS_SEC"1";
"2"
$PN"2"66;
"1"
$PN"1"39;
%"Q_CAP_DIFFBUS"
"2","(-1475,2750)","2","pure_quanta","I284";
;
PART_NUMBER"SP_CH4221MEE01"
VALUE"DIFF BUS_0.22UF"
$LOCATION"C1524"
TOLERANCE"20%"
PACK_TYPE"C0201"
MATERIAL"X6S"
VOLTAGE"6.3V"
PIN_NAMES_ROTATE"TRUE"
CDS_LMAN_SYM_OUTLINE"-25,50,25,-50"
CDS_LIB"pure_quanta"
CDS_LOCATION"C1524"
$SEC"1"
CDS_SEC"1";
"2"
$PN"2"62;
"1"
$PN"1"44;
%"Q_CAP_DIFFBUS"
"2","(-1475,2900)","2","pure_quanta","I285";
;
PART_NUMBER"SP_CH4221MEE01"
VALUE"DIFF BUS_0.22UF"
$LOCATION"C1523"
TOLERANCE"20%"
PACK_TYPE"C0201"
MATERIAL"X6S"
VOLTAGE"6.3V"
PIN_NAMES_ROTATE"TRUE"
CDS_LIB"pure_quanta"
CDS_LMAN_SYM_OUTLINE"-25,50,25,-50"
CDS_LOCATION"C1523"
$SEC"1"
CDS_SEC"1";
"2"
$PN"2"68;
"1"
$PN"1"40;
%"Q_CAP_DIFFBUS"
"2","(-1475,2950)","2","pure_quanta","I286";
;
PART_NUMBER"SP_CH4221MEE01"
VALUE"DIFF BUS_0.22UF"
$LOCATION"C1522"
TOLERANCE"20%"
PACK_TYPE"C0201"
MATERIAL"X6S"
VOLTAGE"6.3V"
PIN_NAMES_ROTATE"TRUE"
CDS_LIB"pure_quanta"
CDS_LMAN_SYM_OUTLINE"-25,50,25,-50"
CDS_LOCATION"C1522"
$SEC"1"
CDS_SEC"1";
"2"
$PN"2"21;
"1"
$PN"1"43;
%"TAP"
"1","(-925,2150)","0","standard","I287";
;
CDS_LIB"standard"
BODY_TYPE"PLUMBING"
HDL_TAP"TRUE";
"B \NAC \NWC"15;
"S \NAC"
BN"8"46;
%"TAP"
"1","(-925,2350)","0","standard","I288";
;
CDS_LIB"standard"
BODY_TYPE"PLUMBING"
HDL_TAP"TRUE";
"B \NAC \NWC"15;
"S \NAC"
BN"9"47;
%"TAP"
"1","(-725,2100)","0","standard","I289";
;
CDS_LIB"standard"
BODY_TYPE"PLUMBING"
HDL_TAP"TRUE";
"B \NAC \NWC"16;
"S \NAC"
BN"8"32;
%"TAP"
"1","(-725,2300)","0","standard","I290";
;
CDS_LIB"standard"
BODY_TYPE"PLUMBING"
HDL_TAP"TRUE";
"B \NAC \NWC"16;
"S \NAC"
BN"9"42;
%"TAP"
"1","(-725,2500)","0","standard","I291";
;
CDS_LIB"standard"
BODY_TYPE"PLUMBING"
HDL_TAP"TRUE";
"B \NAC \NWC"16;
"S \NAC"
BN"10"41;
%"TAP"
"1","(-925,2550)","0","standard","I292";
;
CDS_LIB"standard"
BODY_TYPE"PLUMBING"
HDL_TAP"TRUE";
"B \NAC \NWC"15;
"S \NAC"
BN"10"45;
%"TAP"
"1","(-925,2750)","0","standard","I293";
;
CDS_LIB"standard"
BODY_TYPE"PLUMBING"
HDL_TAP"TRUE";
"B \NAC \NWC"15;
"S \NAC"
BN"11"44;
%"TAP"
"1","(-925,2950)","0","standard","I294";
;
CDS_LIB"standard"
BODY_TYPE"PLUMBING"
HDL_TAP"TRUE";
"B \NAC \NWC"15;
"S \NAC"
BN"12"43;
%"TAP"
"1","(-725,2700)","0","standard","I295";
;
CDS_LIB"standard"
BODY_TYPE"PLUMBING"
HDL_TAP"TRUE";
"B \NAC \NWC"16;
"S \NAC"
BN"11"39;
%"TAP"
"1","(-725,2900)","0","standard","I296";
;
CDS_LIB"standard"
BODY_TYPE"PLUMBING"
HDL_TAP"TRUE";
"B \NAC \NWC"16;
"S \NAC"
BN"12"40;
%"Q_CAP_DIFFBUS"
"2","(-1475,3150)","2","pure_quanta","I297";
;
PART_NUMBER"SP_CH4221MEE01"
VALUE"DIFF BUS_0.22UF"
$LOCATION"C1520"
TOLERANCE"20%"
PACK_TYPE"C0201"
MATERIAL"X6S"
VOLTAGE"6.3V"
PIN_NAMES_ROTATE"TRUE"
CDS_LIB"pure_quanta"
CDS_LMAN_SYM_OUTLINE"-25,50,25,-50"
CDS_LOCATION"C1520"
$SEC"1"
CDS_SEC"1";
"2"
$PN"2"74;
"1"
$PN"1"49;
%"Q_CAP_DIFFBUS"
"2","(-1475,3100)","2","pure_quanta","I298";
;
PART_NUMBER"SP_CH4221MEE01"
VALUE"DIFF BUS_0.22UF"
$LOCATION"C1521"
TOLERANCE"20%"
PACK_TYPE"C0201"
MATERIAL"X6S"
VOLTAGE"6.3V"
PIN_NAMES_ROTATE"TRUE"
CDS_LIB"pure_quanta"
CDS_LMAN_SYM_OUTLINE"-25,50,25,-50"
CDS_LOCATION"C1521"
$SEC"1"
CDS_SEC"1";
"2"
$PN"2"76;
"1"
$PN"1"48;
%"Q_CAP_DIFFBUS"
"2","(-1475,3300)","2","pure_quanta","I299";
;
PART_NUMBER"SP_CH4221MEE01"
VALUE"DIFF BUS_0.22UF"
$LOCATION"C1519"
TOLERANCE"20%"
PACK_TYPE"C0201"
MATERIAL"X6S"
VOLTAGE"6.3V"
PIN_NAMES_ROTATE"TRUE"
CDS_LIB"pure_quanta"
CDS_LMAN_SYM_OUTLINE"-25,50,25,-50"
CDS_LOCATION"C1519"
$SEC"1"
CDS_SEC"1";
"2"
$PN"2"63;
"1"
$PN"1"22;
%"Q_CAP_DIFFBUS"
"2","(-1475,3350)","2","pure_quanta","I300";
;
PART_NUMBER"SP_CH4221MEE01"
VALUE"DIFF BUS_0.22UF"
$LOCATION"C1518"
TOLERANCE"20%"
PACK_TYPE"C0201"
MATERIAL"X6S"
VOLTAGE"6.3V"
PIN_NAMES_ROTATE"TRUE"
CDS_LIB"pure_quanta"
CDS_LMAN_SYM_OUTLINE"-25,50,25,-50"
CDS_LOCATION"C1518"
$SEC"1"
CDS_SEC"1";
"2"
$PN"2"73;
"1"
$PN"1"23;
%"Q_CAP_DIFFBUS"
"2","(-1475,3500)","2","pure_quanta","I301";
;
PART_NUMBER"SP_CH4221MEE01"
VALUE"DIFF BUS_0.22UF"
$LOCATION"C1517"
TOLERANCE"20%"
PACK_TYPE"C0201"
MATERIAL"X6S"
VOLTAGE"6.3V"
PIN_NAMES_ROTATE"TRUE"
CDS_LIB"pure_quanta"
CDS_LMAN_SYM_OUTLINE"-25,50,25,-50"
CDS_LOCATION"C1517"
$SEC"1"
CDS_SEC"1";
"2"
$PN"2"64;
"1"
$PN"1"24;
%"Q_CAP_DIFFBUS"
"2","(-1475,3550)","2","pure_quanta","I302";
;
PART_NUMBER"SP_CH4221MEE01"
VALUE"DIFF BUS_0.22UF"
PACK_TYPE"C0201"
MATERIAL"X6S"
TOLERANCE"20%"
VOLTAGE"6.3V"
$LOCATION"C1516"
PIN_NAMES_ROTATE"TRUE"
CDS_LMAN_SYM_OUTLINE"-25,50,25,-50"
CDS_LIB"pure_quanta"
CDS_LOCATION"C1516"
$SEC"1"
CDS_SEC"1";
"2"
$PN"2"75;
"1"
$PN"1"25;
%"TAP"
"1","(-925,3150)","0","standard","I303";
;
CDS_LIB"standard"
BODY_TYPE"PLUMBING"
HDL_TAP"TRUE";
"B \NAC \NWC"15;
"S \NAC"
BN"13"49;
%"TAP"
"1","(-925,3350)","0","standard","I304";
;
CDS_LIB"standard"
BODY_TYPE"PLUMBING"
HDL_TAP"TRUE";
"B \NAC \NWC"15;
"S \NAC"
BN"14"23;
%"TAP"
"1","(-925,3550)","0","standard","I305";
;
CDS_LIB"standard"
BODY_TYPE"PLUMBING"
HDL_TAP"TRUE";
"B \NAC \NWC"15;
"S \NAC"
BN"15"25;
%"TAP"
"1","(-725,3100)","0","standard","I306";
;
CDS_LIB"standard"
BODY_TYPE"PLUMBING"
HDL_TAP"TRUE";
"B \NAC \NWC"16;
"S \NAC"
BN"13"48;
%"TAP"
"1","(-725,3300)","0","standard","I307";
;
CDS_LIB"standard"
BODY_TYPE"PLUMBING"
HDL_TAP"TRUE";
"B \NAC \NWC"16;
"S \NAC"
BN"14"22;
%"TAP"
"1","(-725,3500)","0","standard","I308";
;
CDS_LIB"standard"
BODY_TYPE"PLUMBING"
HDL_TAP"TRUE";
"B \NAC \NWC"16;
"S \NAC"
BN"15"24;
END.
